(kicad_pcb
	(version 20241229)
	(generator "pcbnew")
	(generator_version "9.0")
	(general
		(thickness 1.62)
		(legacy_teardrops no)
	)
	(paper "A3")
	(title_block
		(title "COM Express 7 Baseboard")
		(date "2025-02-04")
		(rev "1.1.2")
		(company "Antmicro Ltd")
		(comment 1 "www.antmicro.com")
		(comment 9 "footprints 97-101 of 802")
	)
	(layers
		(0 "F.Cu" signal)
		(4 "In1.Cu" signal)
		(6 "In2.Cu" signal)
		(8 "In3.Cu" signal)
		(10 "In4.Cu" signal)
		(12 "In5.Cu" signal)
		(14 "In6.Cu" signal)
		(2 "B.Cu" signal)
		(9 "F.Adhes" user "F.Adhesive")
		(11 "B.Adhes" user "B.Adhesive")
		(13 "F.Paste" user)
		(15 "B.Paste" user)
		(5 "F.SilkS" user "F.Silkscreen")
		(7 "B.SilkS" user "B.Silkscreen")
		(1 "F.Mask" user)
		(3 "B.Mask" user)
		(17 "Dwgs.User" user "User.Drawings")
		(19 "Cmts.User" user "User.Comments")
		(21 "Eco1.User" user "User.Eco1")
		(23 "Eco2.User" user "User.Eco2")
		(25 "Edge.Cuts" user)
		(27 "Margin" user)
		(31 "F.CrtYd" user "F.Courtyard")
		(29 "B.CrtYd" user "B.Courtyard")
		(35 "F.Fab" user)
		(33 "B.Fab" user)
	)
	(footprint "antmicro-footprints:R_0402_1005Metric"
		(layer "F.Cu")
		(at 198.53 83.38 180)
		(descr "Resistor SMD 0402")
		(tags "resistor SMD 0402")
		(property "Reference" "R329"
			(at -1.625 -1.4 0)
			(layer "F.SilkS")
			(effects
				(font
					(size 0.7 0.7)
					(thickness 0.15)
				)
				(justify right bottom)
			)
		)
		(property "Value" "R_5k1_0402"
			(at -1.011843 1.772047 0)
			(layer "F.Fab")
			(effects
				(font
					(size 0.7 0.7)
					(thickness 0.15)
				)
				(justify right bottom)
			)
		)
		(property "Datasheet" "https://www.bourns.com/docs/product-datasheets/cr.pdf"
			(at 0 0 180)
			(layer "F.Fab")
			(hide yes)
			(effects
				(font
					(size 1.27 1.27)
					(thickness 0.15)
				)
			)
		)
		(property "Author" "Antmicro"
			(at 403.22722 166.544326 0)
			(layer "F.Fab")
			(hide yes)
			(effects
				(font
					(size 1 1)
					(thickness 0.15)
				)
			)
		)
		(property "License" "Apache-2.0"
			(at 403.22722 166.544326 0)
			(layer "F.Fab")
			(hide yes)
			(effects
				(font
					(size 1 1)
					(thickness 0.15)
				)
			)
		)
		(property "MPN" "CR0402-FX-5101GLF"
			(at 403.22722 166.544326 0)
			(layer "F.Fab")
			(hide yes)
			(effects
				(font
					(size 1 1)
					(thickness 0.15)
				)
			)
		)
		(property "Manufacturer" "Bourns"
			(at 403.22722 166.544326 0)
			(layer "F.Fab")
			(hide yes)
			(effects
				(font
					(size 1 1)
					(thickness 0.15)
				)
			)
		)
		(property "Tolerance" "1%"
			(at 403.22722 166.544326 0)
			(layer "F.Fab")
			(hide yes)
			(effects
				(font
					(size 1 1)
					(thickness 0.15)
				)
			)
		)
		(property "Val" "5k1"
			(at 403.22722 166.544326 0)
			(layer "F.Fab")
			(hide yes)
			(effects
				(font
					(size 1 1)
					(thickness 0.15)
				)
			)
		)
		(sheetname "Power")
		(sheetfile "power.kicad_sch")
		(attr smd)
		(fp_rect
			(start -0.925 -0.47)
			(end 0.925 0.47)
			(stroke
				(width 0.05)
				(type default)
			)
			(fill no)
			(layer "F.CrtYd")
		)
		(fp_rect
			(start -0.5 -0.25)
			(end 0.5 0.25)
			(stroke
				(width 0.15)
				(type solid)
			)
			(fill no)
			(layer "F.Fab")
		)
		(pad "1" smd roundrect
			(at -0.48 0 180)
			(size 0.59 0.64)
			(layers "F.Cu" "F.Mask" "F.Paste")
			(roundrect_rratio 0.25)
			(net 78 "+1V8")
			(pintype "passive")
			(teardrops
				(best_length_ratio 0.2)
				(max_length 1)
				(best_width_ratio 0.9)
				(max_width 2)
				(curved_edges yes)
				(filter_ratio 0.9)
				(enabled yes)
				(allow_two_segments yes)
				(prefer_zone_connections yes)
			)
		)
		(pad "2" smd roundrect
			(at 0.48 0 180)
			(size 0.59 0.64)
			(layers "F.Cu" "F.Mask" "F.Paste")
			(roundrect_rratio 0.25)
			(net 989 "Net-(Q14-B)")
			(pintype "passive")
			(teardrops
				(best_length_ratio 0.2)
				(max_length 1)
				(best_width_ratio 0.9)
				(max_width 2)
				(curved_edges yes)
				(filter_ratio 0.9)
				(enabled yes)
				(allow_two_segments yes)
				(prefer_zone_connections yes)
			)
		)
	)
	(footprint "antmicro-footprints:R_0402_1005Metric"
		(layer "F.Cu")
		(at 131.9 81.76 -90)
		(descr "Resistor SMD 0402")
		(tags "resistor SMD 0402")
		(property "Reference" "R233"
			(at -3.650001 -0.45 90)
			(layer "F.SilkS")
			(effects
				(font
					(size 0.7 0.7)
					(thickness 0.15)
				)
				(justify right bottom)
			)
		)
		(property "Value" "R_0R_0402"
			(at -1.011843 1.772047 90)
			(layer "F.Fab")
			(effects
				(font
					(size 0.7 0.7)
					(thickness 0.15)
				)
				(justify right bottom)
			)
		)
		(property "Datasheet" "https://industrial.panasonic.com/cdbs/www-data/pdf/RDA0000/AOA0000C301.pdf"
			(at 0 0 270)
			(layer "F.Fab")
			(hide yes)
			(effects
				(font
					(size 1.27 1.27)
					(thickness 0.15)
				)
			)
		)
		(property "Author" "Antmicro"
			(at 50.14 213.66 0)
			(layer "F.Fab")
			(hide yes)
			(effects
				(font
					(size 1 1)
					(thickness 0.15)
				)
			)
		)
		(property "Current" "1A"
			(at 50.14 213.66 0)
			(layer "F.Fab")
			(hide yes)
			(effects
				(font
					(size 1 1)
					(thickness 0.15)
				)
			)
		)
		(property "License" "Apache-2.0"
			(at 50.14 213.66 0)
			(layer "F.Fab")
			(hide yes)
			(effects
				(font
					(size 1 1)
					(thickness 0.15)
				)
			)
		)
		(property "MPN" "ERJ2GE0R00X"
			(at 50.14 213.66 0)
			(layer "F.Fab")
			(hide yes)
			(effects
				(font
					(size 1 1)
					(thickness 0.15)
				)
			)
		)
		(property "Manufacturer" "Panasonic"
			(at 50.14 213.66 0)
			(layer "F.Fab")
			(hide yes)
			(effects
				(font
					(size 1 1)
					(thickness 0.15)
				)
			)
		)
		(property "Public" "False"
			(at 50.14 213.66 0)
			(layer "F.Fab")
			(hide yes)
			(effects
				(font
					(size 1 1)
					(thickness 0.15)
				)
			)
		)
		(property "Tolerance" ""
			(at 50.14 213.66 0)
			(layer "F.Fab")
			(hide yes)
			(effects
				(font
					(size 1 1)
					(thickness 0.15)
				)
			)
		)
		(property "Val" "0R"
			(at 50.14 213.66 0)
			(layer "F.Fab")
			(hide yes)
			(effects
				(font
					(size 1 1)
					(thickness 0.15)
				)
			)
		)
		(sheetname "GPIO expander")
		(sheetfile "gpio_exp.kicad_sch")
		(attr smd)
		(fp_rect
			(start -0.925 -0.47)
			(end 0.925 0.47)
			(stroke
				(width 0.05)
				(type default)
			)
			(fill no)
			(layer "F.CrtYd")
		)
		(fp_rect
			(start -0.5 -0.25)
			(end 0.5 0.25)
			(stroke
				(width 0.15)
				(type solid)
			)
			(fill no)
			(layer "F.Fab")
		)
		(pad "1" smd roundrect
			(at -0.48 0 270)
			(size 0.59 0.64)
			(layers "F.Cu" "F.Mask" "F.Paste")
			(roundrect_rratio 0.25)
			(net 358 "/Com Express 7 MGMT/SMBus.SDA")
			(pintype "passive")
			(teardrops
				(best_length_ratio 0.2)
				(max_length 1)
				(best_width_ratio 0.9)
				(max_width 2)
				(curved_edges yes)
				(filter_ratio 0.9)
				(enabled yes)
				(allow_two_segments yes)
				(prefer_zone_connections yes)
			)
		)
		(pad "2" smd roundrect
			(at 0.48 0 270)
			(size 0.59 0.64)
			(layers "F.Cu" "F.Mask" "F.Paste")
			(roundrect_rratio 0.25)
			(net 634 "Net-(U41-SDA)")
			(pintype "passive")
			(teardrops
				(best_length_ratio 0.2)
				(max_length 1)
				(best_width_ratio 0.9)
				(max_width 2)
				(curved_edges yes)
				(filter_ratio 0.9)
				(enabled yes)
				(allow_two_segments yes)
				(prefer_zone_connections yes)
			)
		)
	)
	(footprint "antmicro-footprints:R_0402_1005Metric"
		(layer "F.Cu")
		(at 219.73 124.9)
		(descr "Resistor SMD 0402")
		(tags "resistor SMD 0402")
		(property "Reference" "R190"
			(at 0.77 0.46 0)
			(layer "F.SilkS")
			(effects
				(font
					(size 0.7 0.7)
					(thickness 0.15)
				)
				(justify left bottom)
			)
		)
		(property "Value" "R_1k_0402"
			(at -1.011843 1.772047 0)
			(layer "F.Fab")
			(effects
				(font
					(size 0.7 0.7)
					(thickness 0.15)
				)
				(justify left bottom)
			)
		)
		(property "Datasheet" "https://www.bourns.com/docs/product-datasheets/cr.pdf"
			(at 0 0 0)
			(layer "F.Fab")
			(hide yes)
			(effects
				(font
					(size 1.27 1.27)
					(thickness 0.15)
				)
			)
		)
		(property "Author" "Antmicro"
			(at 0 0 0)
			(layer "F.Fab")
			(hide yes)
			(effects
				(font
					(size 1 1)
					(thickness 0.15)
				)
			)
		)
		(property "License" "Apache-2.0"
			(at 0 0 0)
			(layer "F.Fab")
			(hide yes)
			(effects
				(font
					(size 1 1)
					(thickness 0.15)
				)
			)
		)
		(property "MPN" "CR0402-FX-1001GLF"
			(at 0 0 0)
			(layer "F.Fab")
			(hide yes)
			(effects
				(font
					(size 1 1)
					(thickness 0.15)
				)
			)
		)
		(property "Manufacturer" "Bourns"
			(at 0 0 0)
			(layer "F.Fab")
			(hide yes)
			(effects
				(font
					(size 1 1)
					(thickness 0.15)
				)
			)
		)
		(property "Public" "False"
			(at 0 0 0)
			(layer "F.Fab")
			(hide yes)
			(effects
				(font
					(size 1 1)
					(thickness 0.15)
				)
			)
		)
		(property "Tolerance" "1%"
			(at 0 0 0)
			(layer "F.Fab")
			(hide yes)
			(effects
				(font
					(size 1 1)
					(thickness 0.15)
				)
			)
		)
		(property "Val" "1k"
			(at 0 0 0)
			(layer "F.Fab")
			(hide yes)
			(effects
				(font
					(size 1 1)
					(thickness 0.15)
				)
			)
		)
		(sheetname "PCIe misc")
		(sheetfile "pcie_misc.kicad_sch")
		(attr smd)
		(fp_rect
			(start -0.925 -0.47)
			(end 0.925 0.47)
			(stroke
				(width 0.05)
				(type default)
			)
			(fill no)
			(layer "F.CrtYd")
		)
		(fp_rect
			(start -0.5 -0.25)
			(end 0.5 0.25)
			(stroke
				(width 0.15)
				(type solid)
			)
			(fill no)
			(layer "F.Fab")
		)
		(pad "1" smd roundrect
			(at -0.48 0)
			(size 0.59 0.64)
			(layers "F.Cu" "F.Mask" "F.Paste")
			(roundrect_rratio 0.25)
			(net 609 "Net-(U37-~{CKPWRGD_PD})")
			(pintype "passive")
			(teardrops
				(best_length_ratio 0.2)
				(max_length 1)
				(best_width_ratio 0.9)
				(max_width 2)
				(curved_edges yes)
				(filter_ratio 0.9)
				(enabled yes)
				(allow_two_segments yes)
				(prefer_zone_connections yes)
			)
		)
		(pad "2" smd roundrect
			(at 0.48 0)
			(size 0.59 0.64)
			(layers "F.Cu" "F.Mask" "F.Paste")
			(roundrect_rratio 0.25)
			(net 2 "+3V3")
			(pintype "passive")
			(teardrops
				(best_length_ratio 0.2)
				(max_length 1)
				(best_width_ratio 0.9)
				(max_width 2)
				(curved_edges yes)
				(filter_ratio 0.9)
				(enabled yes)
				(allow_two_segments yes)
				(prefer_zone_connections yes)
			)
		)
	)
	(footprint "antmicro-footprints:TP_SMD_0.75mm"
		(layer "F.Cu")
		(at 188.708611 72.802163 -90)
		(property "Reference" "TP103"
			(at 0 -0.6 90)
			(layer "F.SilkS")
			(hide yes)
			(effects
				(font
					(size 0.7 0.7)
					(thickness 0.15)
				)
				(justify right bottom)
			)
		)
		(property "Value" "TP_0.75mm_SMD"
			(at 0 1.2 90)
			(layer "F.Fab")
			(effects
				(font
					(size 0.7 0.7)
					(thickness 0.15)
				)
				(justify right bottom)
			)
		)
		(property "Author" "Antmicro"
			(at 115.906448 261.510774 0)
			(layer "F.Fab")
			(hide yes)
			(effects
				(font
					(size 1 1)
					(thickness 0.15)
				)
			)
		)
		(property "License" "Apache-2.0"
			(at 115.906448 261.510774 0)
			(layer "F.Fab")
			(hide yes)
			(effects
				(font
					(size 1 1)
					(thickness 0.15)
				)
			)
		)
		(property "MPN" ""
			(at 115.906448 261.510774 0)
			(layer "F.Fab")
			(hide yes)
			(effects
				(font
					(size 1 1)
					(thickness 0.15)
				)
			)
		)
		(property "Manufacturer" ""
			(at 115.906448 261.510774 0)
			(layer "F.Fab")
			(hide yes)
			(effects
				(font
					(size 1 1)
					(thickness 0.15)
				)
			)
		)
		(property "Public" "False"
			(at 115.906448 261.510774 0)
			(layer "F.Fab")
			(hide yes)
			(effects
				(font
					(size 1 1)
					(thickness 0.15)
				)
			)
		)
		(sheetname "Power")
		(sheetfile "power.kicad_sch")
		(attr exclude_from_pos_files exclude_from_bom)
		(fp_circle
			(center 0 0)
			(end 0.475 0)
			(stroke
				(width 0.05)
				(type default)
			)
			(fill no)
			(layer "F.CrtYd")
		)
		(pad "1" smd circle
			(at 0 0 270)
			(size 0.75 0.75)
			(layers "F.Cu" "F.Mask")
			(net 77 "+5V_AON")
			(pinfunction "1")
			(pintype "passive")
			(teardrops
				(best_length_ratio 0.4)
				(max_length 1)
				(best_width_ratio 0.9)
				(max_width 2)
				(curved_edges yes)
				(filter_ratio 0.9)
				(enabled yes)
				(allow_two_segments yes)
				(prefer_zone_connections yes)
			)
		)
	)
	(footprint "antmicro-footprints:TSSOP-8_3x3mm_P0.65mm"
		(layer "F.Cu")
		(at 121 73.61 90)
		(property "Reference" "U7"
			(at 1.3 2.8 90)
			(layer "F.SilkS")
			(effects
				(font
					(size 0.7 0.7)
					(thickness 0.15)
				)
				(justify left bottom)
			)
		)
		(property "Value" "NTS0102_TSSOP"
			(at 0 2.8 90)
			(layer "F.Fab")
			(effects
				(font
					(size 0.7 0.7)
					(thickness 0.15)
				)
				(justify left bottom)
			)
		)
		(property "Datasheet" "https://www.mouser.com/datasheet/2/302/NTS0102-1127324.pdf"
			(at 0 0 90)
			(layer "F.Fab")
			(hide yes)
			(effects
				(font
					(size 1.27 1.27)
					(thickness 0.15)
				)
			)
		)
		(property "Author" "Antmicro"
			(at 194.61 -47.39 0)
			(layer "F.Fab")
			(hide yes)
			(effects
				(font
					(size 1 1)
					(thickness 0.15)
				)
			)
		)
		(property "License" "Apache-2.0"
			(at 194.61 -47.39 0)
			(layer "F.Fab")
			(hide yes)
			(effects
				(font
					(size 1 1)
					(thickness 0.15)
				)
			)
		)
		(property "MPN" "NTS0102DP"
			(at 194.61 -47.39 0)
			(layer "F.Fab")
			(hide yes)
			(effects
				(font
					(size 1 1)
					(thickness 0.15)
				)
			)
		)
		(property "Manufacturer" "NXP"
			(at 194.61 -47.39 0)
			(layer "F.Fab")
			(hide yes)
			(effects
				(font
					(size 1 1)
					(thickness 0.15)
				)
			)
		)
		(sheetname "USB-C console")
		(sheetfile "usb-c_console.kicad_sch")
		(attr smd)
		(fp_line
			(start -1.525 -1.537)
			(end 1.552 -1.539)
			(stroke
				(width 0.15)
				(type solid)
			)
			(layer "F.SilkS")
		)
		(fp_line
			(start -1.55 1.561)
			(end 1.552 1.561)
			(stroke
				(width 0.15)
				(type solid)
			)
			(layer "F.SilkS")
		)
		(fp_circle
			(center -1.87 -1.4)
			(end -1.82 -1.4)
			(stroke
				(width 0.15)
				(type solid)
			)
			(fill yes)
			(layer "F.SilkS")
		)
		(fp_rect
			(start -3.15 -1.789)
			(end 3.15 1.811)
			(stroke
				(width 0.05)
				(type solid)
			)
			(fill no)
			(layer "F.CrtYd")
		)
		(fp_line
			(start 1.552 -1.539)
			(end 1.552 1.561)
			(stroke
				(width 0.15)
				(type solid)
			)
			(layer "F.Fab")
		)
		(fp_line
			(start -0.949 -1.539)
			(end 1.552 -1.539)
			(stroke
				(width 0.15)
				(type solid)
			)
			(layer "F.Fab")
		)
		(fp_line
			(start -1.55 -0.937)
			(end -0.949 -1.539)
			(stroke
				(width 0.15)
				(type solid)
			)
			(layer "F.Fab")
		)
		(fp_line
			(start -1.55 -0.937)
			(end -1.55 1.561)
			(stroke
				(width 0.15)
				(type solid)
			)
			(layer "F.Fab")
		)
		(fp_line
			(start -1.55 1.561)
			(end 1.552 1.561)
			(stroke
				(width 0.15)
				(type solid)
			)
			(layer "F.Fab")
		)
		(pad "1" smd roundrect
			(at -2.148 -0.962 90)
			(size 1.47 0.4)
			(layers "F.Cu" "F.Mask" "F.Paste")
			(roundrect_rratio 0.25)
			(net 700 "/USB-C console/FTDI_TX")
			(pinfunction "B_{2}")
			(pintype "bidirectional")
			(teardrops
				(best_length_ratio 0.2)
				(max_length 1)
				(best_width_ratio 0.9)
				(max_width 2)
				(curved_edges yes)
				(filter_ratio 0.9)
				(enabled yes)
				(allow_two_segments yes)
				(prefer_zone_connections yes)
			)
		)
		(pad "2" smd roundrect
			(at -2.148 -0.313 90)
			(size 1.47 0.4)
			(layers "F.Cu" "F.Mask" "F.Paste")
			(roundrect_rratio 0.25)
			(net 1 "GND")
			(pinfunction "GND")
			(pintype "power_in")
			(teardrops
				(best_length_ratio 0.2)
				(max_length 1)
				(best_width_ratio 0.9)
				(max_width 2)
				(curved_edges yes)
				(filter_ratio 0.9)
				(enabled yes)
				(allow_two_segments yes)
				(prefer_zone_connections yes)
			)
		)
		(pad "3" smd roundrect
			(at -2.148 0.338 90)
			(size 1.47 0.4)
			(layers "F.Cu" "F.Mask" "F.Paste")
			(roundrect_rratio 0.25)
			(net 2 "+3V3")
			(pinfunction "VCC_{A}")
			(pintype "power_in")
			(teardrops
				(best_length_ratio 0.2)
				(max_length 1)
				(best_width_ratio 0.9)
				(max_width 2)
				(curved_edges yes)
				(filter_ratio 0.9)
				(enabled yes)
				(allow_two_segments yes)
				(prefer_zone_connections yes)
			)
		)
		(pad "4" smd roundrect
			(at -2.148 0.987 90)
			(size 1.47 0.4)
			(layers "F.Cu" "F.Mask" "F.Paste")
			(roundrect_rratio 0.25)
			(net 572 "Net-(U7-A_{2})")
			(pinfunction "A_{2}")
			(pintype "bidirectional")
			(teardrops
				(best_length_ratio 0.2)
				(max_length 1)
				(best_width_ratio 0.9)
				(max_width 2)
				(curved_edges yes)
				(filter_ratio 0.9)
				(enabled yes)
				(allow_two_segments yes)
				(prefer_zone_connections yes)
			)
		)
		(pad "5" smd roundrect
			(at 2.151 0.987 90)
			(size 1.47 0.4)
			(layers "F.Cu" "F.Mask" "F.Paste")
			(roundrect_rratio 0.25)
			(net 571 "Net-(U7-A_{1})")
			(pinfunction "A_{1}")
			(pintype "bidirectional")
			(teardrops
				(best_length_ratio 0.2)
				(max_length 1)
				(best_width_ratio 0.9)
				(max_width 2)
				(curved_edges yes)
				(filter_ratio 0.9)
				(enabled yes)
				(allow_two_segments yes)
				(prefer_zone_connections yes)
			)
		)
		(pad "6" smd roundrect
			(at 2.151 0.338 90)
			(size 1.47 0.4)
			(layers "F.Cu" "F.Mask" "F.Paste")
			(roundrect_rratio 0.25)
			(net 2 "+3V3")
			(pinfunction "OE")
			(pintype "input")
			(teardrops
				(best_length_ratio 0.2)
				(max_length 1)
				(best_width_ratio 0.9)
				(max_width 2)
				(curved_edges yes)
				(filter_ratio 0.9)
				(enabled yes)
				(allow_two_segments yes)
				(prefer_zone_connections yes)
			)
		)
		(pad "7" smd roundrect
			(at 2.151 -0.313 90)
			(size 1.47 0.4)
			(layers "F.Cu" "F.Mask" "F.Paste")
			(roundrect_rratio 0.25)
			(net 58 "/USB-C console/VBUS_FTDI")
			(pinfunction "VCC_{B}")
			(pintype "power_in")
			(teardrops
				(best_length_ratio 0.2)
				(max_length 1)
				(best_width_ratio 0.9)
				(max_width 2)
				(curved_edges yes)
				(filter_ratio 0.9)
				(enabled yes)
				(allow_two_segments yes)
				(prefer_zone_connections yes)
			)
		)
		(pad "8" smd roundrect
			(at 2.151 -0.962 90)
			(size 1.47 0.4)
			(layers "F.Cu" "F.Mask" "F.Paste")
			(roundrect_rratio 0.25)
			(net 699 "/USB-C console/FTDI_RX")
			(pinfunction "B_{1}")
			(pintype "bidirectional")
			(teardrops
				(best_length_ratio 0.2)
				(max_length 1)
				(best_width_ratio 0.9)
				(max_width 2)
				(curved_edges yes)
				(filter_ratio 0.9)
				(enabled yes)
				(allow_two_segments yes)
				(prefer_zone_connections yes)
			)
		)
	)
)
